FILE_TYPE = CONNECTIVITY;
{Allegro Design Entry HDL 17.4-2019 S026 (4007227) 1/17/2022}
"PAGE_NUMBER" = 407;
0"NC";
1"P5E_CPU0_P1_TX_BUF_C_DN<7:0>";
2"P5E_CPU0_P1_TX_BUF_C_DP<7:0>";
3"P5E_CPU0_P1_TX_BUF_DN<7:0>";
4"P5E_CPU0_P1_TX_BUF_DP<7:0>";
5"P5E_CPU0_P1_TX_BUF_C_DN<15:8>";
6"P5E_CPU0_P1_TX_BUF_C_DP<15:8>";
7"P5E_CPU0_P1_TX_BUF_DN<15:8>";
8"P5E_CPU0_P1_TX_BUF_DP<15:8>";
9"P5E_CPU0_P1_TX_BUF_DN<7:0>";
10"P5E_CPU0_P1_TX_BUF_DP<7:0>";
11"P5E_CPU0_P1_TX_BUF_DN<15:8>";
12"P5E_CPU0_P1_TX_BUF_DP<15:8>";
13"P5E_CPU0_P1_TX_BUF_DP<9>";
14"P5E_CPU0_P1_TX_BUF_DP<14>";
15"P5E_CPU0_P1_TX_BUF_DN<14>";
16"P5E_CPU0_P1_TX_BUF_DP<13>";
17"P5E_CPU0_P1_TX_BUF_DP<11>";
18"P5E_CPU0_P1_TX_BUF_DN<12>";
19"P5E_CPU0_P1_TX_BUF_DN<0>";
20"P5E_CPU0_P1_TX_BUF_DN<1>";
21"P5E_CPU0_P1_TX_BUF_DP<5>";
22"P5E_CPU0_P1_TX_BUF_DP<3>";
23"P5E_CPU0_P1_TX_BUF_DN<4>";
24"P5E_CPU0_P1_TX_BUF_DN<5>";
25"P5E_CPU0_P1_TX_BUF_DP<6>";
26"P5E_CPU0_P1_TX_BUF_DN<13>";
27"P5E_CPU0_P1_TX_BUF_DP<7>";
28"P5E_CPU0_P1_TX_BUF_DP<4>";
29"P5E_CPU0_P1_TX_BUF_DP<1>";
30"P5E_CPU0_P1_TX_BUF_DN<15>";
31"P5E_CPU0_P1_TX_BUF_DP<15>";
32"P5E_CPU0_P1_TX_BUF_DP<8>";
33"P5E_CPU0_P1_TX_BUF_DN<9>";
34"P5E_CPU0_P1_TX_BUF_DN<10>";
35"P5E_CPU0_P1_TX_BUF_DP<10>";
36"P5E_CPU0_P1_TX_BUF_DN<11>";
37"P5E_CPU0_P1_TX_BUF_DP<12>";
38"P5E_CPU0_P1_TX_BUF_DN<8>";
39"P5E_CPU0_P1_TX_BUF_DN<7>";
40"P5E_CPU0_P1_TX_BUF_DP<0>";
41"P5E_CPU0_P1_TX_BUF_DN<2>";
42"P5E_CPU0_P1_TX_BUF_DP<2>";
43"P5E_CPU0_P1_TX_BUF_DN<6>";
44"P5E_CPU0_P1_TX_BUF_DN<3>";
45"P5E_CPU0_P1_TX_BUF_C_DN<8>";
46"P5E_CPU0_P1_TX_BUF_C_DP<8>";
47"P5E_CPU0_P1_TX_BUF_DP<8>";
48"P5E_CPU0_P1_TX_BUF_DN<8>";
49"P5E_CPU0_P1_TX_BUF_C_DP<9>";
50"P5E_CPU0_P1_TX_BUF_C_DN<9>";
51"P5E_CPU0_P1_TX_BUF_C_DP<11>";
52"P5E_CPU0_P1_TX_BUF_C_DN<11>";
53"P5E_CPU0_P1_TX_BUF_C_DP<12>";
54"P5E_CPU0_P1_TX_BUF_C_DN<12>";
55"P5E_CPU0_P1_TX_BUF_C_DP<13>";
56"P5E_CPU0_P1_TX_BUF_C_DN<13>";
57"P5E_CPU0_P1_TX_BUF_C_DP<14>";
58"P5E_CPU0_P1_TX_BUF_C_DN<14>";
59"P5E_CPU0_P1_TX_BUF_C_DP<15>";
60"P5E_CPU0_P1_TX_BUF_C_DN<15>";
61"P5E_CPU0_P1_TX_BUF_DP<9>";
62"P5E_CPU0_P1_TX_BUF_DP<10>";
63"P5E_CPU0_P1_TX_BUF_DP<11>";
64"P5E_CPU0_P1_TX_BUF_DN<10>";
65"P5E_CPU0_P1_TX_BUF_DN<9>";
66"P5E_CPU0_P1_TX_BUF_DP<12>";
67"P5E_CPU0_P1_TX_BUF_DP<13>";
68"P5E_CPU0_P1_TX_BUF_DN<13>";
69"P5E_CPU0_P1_TX_BUF_DN<12>";
70"P5E_CPU0_P1_TX_BUF_DN<11>";
71"P5E_CPU0_P1_TX_BUF_DP<14>";
72"P5E_CPU0_P1_TX_BUF_DP<15>";
73"P5E_CPU0_P1_TX_BUF_DN<14>";
74"P5E_CPU0_P1_TX_BUF_DN<15>";
75"P5E_CPU0_P1_TX_BUF_C_DP<10>";
76"P5E_CPU0_P1_TX_BUF_C_DN<10>";
77"P5E_CPU0_P1_TX_BUF_C_DN<1>";
78"P5E_CPU0_P1_TX_BUF_C_DP<1>";
79"P5E_CPU0_P1_TX_BUF_C_DP<2>";
80"P5E_CPU0_P1_TX_BUF_C_DN<2>";
81"P5E_CPU0_P1_TX_BUF_C_DP<3>";
82"P5E_CPU0_P1_TX_BUF_C_DN<3>";
83"P5E_CPU0_P1_TX_BUF_DP<0>";
84"P5E_CPU0_P1_TX_BUF_DP<1>";
85"P5E_CPU0_P1_TX_BUF_DP<2>";
86"P5E_CPU0_P1_TX_BUF_DP<3>";
87"P5E_CPU0_P1_TX_BUF_C_DP<4>";
88"P5E_CPU0_P1_TX_BUF_DP<4>";
89"P5E_CPU0_P1_TX_BUF_C_DN<4>";
90"P5E_CPU0_P1_TX_BUF_C_DN<5>";
91"P5E_CPU0_P1_TX_BUF_C_DP<5>";
92"P5E_CPU0_P1_TX_BUF_C_DP<6>";
93"P5E_CPU0_P1_TX_BUF_C_DN<6>";
94"P5E_CPU0_P1_TX_BUF_C_DN<7>";
95"P5E_CPU0_P1_TX_BUF_C_DP<7>";
96"P5E_CPU0_P1_TX_BUF_DP<5>";
97"P5E_CPU0_P1_TX_BUF_DP<6>";
98"P5E_CPU0_P1_TX_BUF_DP<7>";
99"P5E_CPU0_P1_TX_BUF_DN<0>";
100"P5E_CPU0_P1_TX_BUF_DN<1>";
101"P5E_CPU0_P1_TX_BUF_DN<2>";
102"P5E_CPU0_P1_TX_BUF_DN<3>";
103"P5E_CPU0_P1_TX_BUF_DN<4>";
104"P5E_CPU0_P1_TX_BUF_DN<5>";
105"P5E_CPU0_P1_TX_BUF_DN<6>";
106"P5E_CPU0_P1_TX_BUF_DN<7>";
107"P5E_CPU0_P1_TX_BUF_C_DP<0>";
108"P5E_CPU0_P1_TX_BUF_C_DN<0>";
%"TAP"
"1","(-3125,1000)","2","standard","I10";
;
CDS_LIB"standard"
BODY_TYPE"PLUMBING"
HDL_TAP"TRUE";
"B \NAC \NWC"4;
"S \NAC"
BN"6"97;
%"TAP"
"1","(-7650,2000)","2","standard","I100";
;
CDS_LIB"standard"
BODY_TYPE"PLUMBING"
HDL_TAP"TRUE";
"B \NAC \NWC"8;
"S \NAC"
BN"9"61;
%"TAP"
"1","(-7650,2200)","2","standard","I101";
;
CDS_LIB"standard"
BODY_TYPE"PLUMBING"
HDL_TAP"TRUE";
"B \NAC \NWC"8;
"S \NAC"
BN"8"47;
%"Q_CAP_DIFFBUS"
"2","(-6925,2000)","2","pure_quanta","I102";
;
LOCATION"C6551"
$SEC"1"
CDS_SEC"1"
VALUE"DIFF BUS_0.22UF"
TOLERANCE"20%"
PACK_TYPE"C0201"
MATERIAL"X6S"
VOLTAGE"6.3V"
PIN_NAMES_ROTATE"TRUE"
CDS_LIB"pure_quanta"
CDS_LMAN_SYM_OUTLINE"-25,50,25,-50"
PART_NUMBER"SP_CH4221MEE01"
LOCATION"C6551";
"2"
$PN"2"61;
"1"
$PN"1"49;
%"Q_CAP_DIFFBUS"
"2","(-6925,1950)","2","pure_quanta","I103";
;
LOCATION"C6552"
$SEC"1"
CDS_SEC"1"
VALUE"DIFF BUS_0.22UF"
TOLERANCE"20%"
PACK_TYPE"C0201"
MATERIAL"X6S"
VOLTAGE"6.3V"
PIN_NAMES_ROTATE"TRUE"
CDS_LIB"pure_quanta"
CDS_LMAN_SYM_OUTLINE"-25,50,25,-50"
PART_NUMBER"SP_CH4221MEE01"
LOCATION"C6552";
"2"
$PN"2"65;
"1"
$PN"1"50;
%"Q_CAP_DIFFBUS"
"2","(-6925,2150)","2","pure_quanta","I104";
;
LOCATION"C6550"
$SEC"1"
CDS_SEC"1"
VALUE"DIFF BUS_0.22UF"
TOLERANCE"20%"
PACK_TYPE"C0201"
MATERIAL"X6S"
VOLTAGE"6.3V"
PIN_NAMES_ROTATE"TRUE"
CDS_LIB"pure_quanta"
CDS_LMAN_SYM_OUTLINE"-25,50,25,-50"
PART_NUMBER"SP_CH4221MEE01"
LOCATION"C6550";
"2"
$PN"2"48;
"1"
$PN"1"45;
%"Q_CAP_DIFFBUS"
"2","(-6925,2200)","2","pure_quanta","I105";
;
LOCATION"C6549"
$SEC"1"
CDS_SEC"1"
TOLERANCE"20%"
MATERIAL"X6S"
PACK_TYPE"C0201"
VOLTAGE"6.3V"
VALUE"DIFF BUS_0.22UF"
PIN_NAMES_ROTATE"TRUE"
CDS_LMAN_SYM_OUTLINE"-25,50,25,-50"
CDS_LIB"pure_quanta"
PART_NUMBER"SP_CH4221MEE01"
LOCATION"C6549";
"2"
$PN"2"47;
"1"
$PN"1"46;
%"TAP"
"1","(-6375,800)","0","standard","I106";
;
CDS_LIB"standard"
BODY_TYPE"PLUMBING"
HDL_TAP"TRUE";
"B \NAC \NWC"6;
"S \NAC"
BN"15"59;
%"TAP"
"1","(-6175,750)","0","standard","I107";
;
CDS_LIB"standard"
BODY_TYPE"PLUMBING"
HDL_TAP"TRUE";
"B \NAC \NWC"5;
"S \NAC"
BN"15"60;
%"TAP"
"1","(-6375,1000)","0","standard","I108";
;
CDS_LIB"standard"
BODY_TYPE"PLUMBING"
HDL_TAP"TRUE";
"B \NAC \NWC"6;
"S \NAC"
BN"14"57;
%"TAP"
"1","(-6375,1200)","0","standard","I109";
;
CDS_LIB"standard"
BODY_TYPE"PLUMBING"
HDL_TAP"TRUE";
"B \NAC \NWC"6;
"S \NAC"
BN"13"55;
%"TAP"
"1","(-3125,1200)","2","standard","I11";
;
CDS_LIB"standard"
BODY_TYPE"PLUMBING"
HDL_TAP"TRUE";
"B \NAC \NWC"4;
"S \NAC"
BN"5"96;
%"TAP"
"1","(-6175,950)","0","standard","I110";
;
CDS_LIB"standard"
BODY_TYPE"PLUMBING"
HDL_TAP"TRUE";
"B \NAC \NWC"5;
"S \NAC"
BN"14"58;
%"TAP"
"1","(-6175,1150)","0","standard","I111";
;
CDS_LIB"standard"
BODY_TYPE"PLUMBING"
HDL_TAP"TRUE";
"B \NAC \NWC"5;
"S \NAC"
BN"13"56;
%"TAP"
"1","(-6175,1350)","0","standard","I112";
;
CDS_LIB"standard"
BODY_TYPE"PLUMBING"
HDL_TAP"TRUE";
"B \NAC \NWC"5;
"S \NAC"
BN"12"54;
%"TAP"
"1","(-6375,1400)","0","standard","I113";
;
CDS_LIB"standard"
BODY_TYPE"PLUMBING"
HDL_TAP"TRUE";
"B \NAC \NWC"6;
"S \NAC"
BN"12"53;
%"TAP"
"1","(-6375,1600)","0","standard","I114";
;
CDS_LIB"standard"
BODY_TYPE"PLUMBING"
HDL_TAP"TRUE";
"B \NAC \NWC"6;
"S \NAC"
BN"11"51;
%"TAP"
"1","(-6375,1800)","0","standard","I115";
;
CDS_LIB"standard"
BODY_TYPE"PLUMBING"
HDL_TAP"TRUE";
"B \NAC \NWC"6;
"S \NAC"
BN"10"75;
%"TAP"
"1","(-6175,1550)","0","standard","I116";
;
CDS_LIB"standard"
BODY_TYPE"PLUMBING"
HDL_TAP"TRUE";
"B \NAC \NWC"5;
"S \NAC"
BN"11"52;
%"TAP"
"1","(-6175,1750)","0","standard","I117";
;
CDS_LIB"standard"
BODY_TYPE"PLUMBING"
HDL_TAP"TRUE";
"B \NAC \NWC"5;
"S \NAC"
BN"10"76;
%"TAP"
"1","(-6375,2000)","0","standard","I118";
;
CDS_LIB"standard"
BODY_TYPE"PLUMBING"
HDL_TAP"TRUE";
"B \NAC \NWC"6;
"S \NAC"
BN"9"49;
%"TAP"
"1","(-6375,2200)","0","standard","I119";
;
CDS_LIB"standard"
BODY_TYPE"PLUMBING"
HDL_TAP"TRUE";
"B \NAC \NWC"6;
"S \NAC"
BN"8"46;
%"TAP"
"1","(-3125,1400)","2","standard","I12";
;
CDS_LIB"standard"
BODY_TYPE"PLUMBING"
HDL_TAP"TRUE";
"B \NAC \NWC"4;
"S \NAC"
BN"4"88;
%"TAP"
"1","(-6175,1950)","0","standard","I120";
;
CDS_LIB"standard"
BODY_TYPE"PLUMBING"
HDL_TAP"TRUE";
"B \NAC \NWC"5;
"S \NAC"
BN"9"50;
%"TAP"
"1","(-6175,2150)","0","standard","I121";
;
CDS_LIB"standard"
BODY_TYPE"PLUMBING"
HDL_TAP"TRUE";
"B \NAC \NWC"5;
"S \NAC"
BN"8"45;
%"TAP"
"1","(-1875,3350)","0","standard","I122";
;
CDS_LIB"standard"
BODY_TYPE"PLUMBING"
HDL_TAP"TRUE";
"B \NAC \NWC"10;
"S \NAC"
BN"0"40;
%"TAP"
"1","(-1675,3250)","0","standard","I123";
;
CDS_LIB"standard"
BODY_TYPE"PLUMBING"
HDL_TAP"TRUE";
"B \NAC \NWC"9;
"S \NAC"
BN"0"19;
%"TAP"
"1","(-1875,3700)","0","standard","I124";
;
CDS_LIB"standard"
BODY_TYPE"PLUMBING"
HDL_TAP"TRUE";
"B \NAC \NWC"10;
"S \NAC"
BN"1"29;
%"TAP"
"1","(-1675,3600)","0","standard","I125";
;
CDS_LIB"standard"
BODY_TYPE"PLUMBING"
HDL_TAP"TRUE";
"B \NAC \NWC"9;
"S \NAC"
BN"1"20;
%"TAP"
"1","(-1875,4050)","0","standard","I128";
;
CDS_LIB"standard"
BODY_TYPE"PLUMBING"
HDL_TAP"TRUE";
"B \NAC \NWC"10;
"S \NAC"
BN"2"42;
%"TAP"
"1","(-1675,3950)","0","standard","I129";
;
CDS_LIB"standard"
BODY_TYPE"PLUMBING"
HDL_TAP"TRUE";
"B \NAC \NWC"9;
"S \NAC"
BN"2"41;
%"TAP"
"1","(-3125,1600)","2","standard","I13";
;
CDS_LIB"standard"
BODY_TYPE"PLUMBING"
HDL_TAP"TRUE";
"B \NAC \NWC"4;
"S \NAC"
BN"3"86;
%"TAP"
"1","(-1675,4300)","0","standard","I130";
;
CDS_LIB"standard"
BODY_TYPE"PLUMBING"
HDL_TAP"TRUE";
"B \NAC \NWC"9;
"S \NAC"
BN"3"44;
%"TAP"
"1","(-1875,4400)","0","standard","I131";
;
CDS_LIB"standard"
BODY_TYPE"PLUMBING"
HDL_TAP"TRUE";
"B \NAC \NWC"10;
"S \NAC"
BN"3"22;
%"TAP"
"1","(-1875,4750)","0","standard","I132";
;
CDS_LIB"standard"
BODY_TYPE"PLUMBING"
HDL_TAP"TRUE";
"B \NAC \NWC"10;
"S \NAC"
BN"4"28;
%"TAP"
"1","(-1675,4650)","0","standard","I133";
;
CDS_LIB"standard"
BODY_TYPE"PLUMBING"
HDL_TAP"TRUE";
"B \NAC \NWC"9;
"S \NAC"
BN"4"23;
%"TAP"
"1","(-1875,5100)","0","standard","I134";
;
CDS_LIB"standard"
BODY_TYPE"PLUMBING"
HDL_TAP"TRUE";
"B \NAC \NWC"10;
"S \NAC"
BN"5"21;
%"TAP"
"1","(-1675,5000)","0","standard","I135";
;
CDS_LIB"standard"
BODY_TYPE"PLUMBING"
HDL_TAP"TRUE";
"B \NAC \NWC"9;
"S \NAC"
BN"5"24;
%"TAP"
"1","(-1675,5350)","0","standard","I136";
;
CDS_LIB"standard"
BODY_TYPE"PLUMBING"
HDL_TAP"TRUE";
"B \NAC \NWC"9;
"S \NAC"
BN"6"43;
%"TAP"
"1","(-1875,5450)","0","standard","I137";
;
CDS_LIB"standard"
BODY_TYPE"PLUMBING"
HDL_TAP"TRUE";
"B \NAC \NWC"10;
"S \NAC"
BN"6"25;
%"TAP"
"1","(-1875,5800)","0","standard","I138";
;
CDS_LIB"standard"
BODY_TYPE"PLUMBING"
HDL_TAP"TRUE";
"B \NAC \NWC"10;
"S \NAC"
BN"7"27;
%"TAP"
"1","(-1675,5700)","0","standard","I139";
;
CDS_LIB"standard"
BODY_TYPE"PLUMBING"
HDL_TAP"TRUE";
"B \NAC \NWC"9;
"S \NAC"
BN"7"39;
%"TAP"
"1","(-3125,1800)","2","standard","I14";
;
CDS_LIB"standard"
BODY_TYPE"PLUMBING"
HDL_TAP"TRUE";
"B \NAC \NWC"4;
"S \NAC"
BN"2"85;
%"PT5161LRS"
"11","(-2600,4550)","0","pure_quanta","I142";
;
LOCATION"U6011"
$SEC"11"
CDS_SEC"11"
MATERIAL"IC"
VALUE"PT5161LRS"
PART_TYPE"SMLF"
CDS_LIB"pure_quanta"
CDS_LMAN_SYM_OUTLINE"-350,1450,300,-1400"
NEEDS_NO_SIZE"TRUE"
PART_NUMBER"AJ051610U03";
"B_PETN15"
$PN"EW10"19;
"B_PETP15"
$PN"EU7"40;
"B_PETN14"
$PN"EM10"20;
"B_PETP14"
$PN"EK7"29;
"B_PETN13"
$PN"EE10"41;
"B_PETP13"
$PN"EC7"42;
"B_PETN12"
$PN"DV10"44;
"B_PETP12"
$PN"DT7"22;
"B_PETN11"
$PN"DL10"23;
"B_PETP11"
$PN"DJ7"28;
"B_PETN10"
$PN"DD10"24;
"B_PETP10"
$PN"DB7"21;
"B_PETN9"
$PN"CU10"43;
"B_PETP9"
$PN"CR7"25;
"B_PETN8"
$PN"CK10"39;
"B_PETP8"
$PN"CH7"27;
%"Q_CAP_DIFFBUS"
"2","(-2400,750)","2","pure_quanta","I15";
;
LOCATION"C6548"
$SEC"1"
CDS_SEC"1"
VALUE"DIFF BUS_0.22UF"
CDS_LMAN_SYM_OUTLINE"-25,50,25,-50"
CDS_LIB"pure_quanta"
PIN_NAMES_ROTATE"TRUE"
VOLTAGE"6.3V"
MATERIAL"X6S"
PACK_TYPE"C0201"
TOLERANCE"20%"
PART_NUMBER"SP_CH4221MEE01"
LOCATION"C6548";
"2"
$PN"2"106;
"1"
$PN"1"94;
%"Q_CAP_DIFFBUS"
"2","(-2400,800)","2","pure_quanta","I16";
;
LOCATION"C6547"
$SEC"1"
CDS_SEC"1"
VALUE"DIFF BUS_0.22UF"
CDS_LMAN_SYM_OUTLINE"-25,50,25,-50"
CDS_LIB"pure_quanta"
PIN_NAMES_ROTATE"TRUE"
VOLTAGE"6.3V"
MATERIAL"X6S"
PACK_TYPE"C0201"
TOLERANCE"20%"
PART_NUMBER"SP_CH4221MEE01"
LOCATION"C6547";
"2"
$PN"2"98;
"1"
$PN"1"95;
%"TAP"
"1","(-1650,750)","0","standard","I17";
;
CDS_LIB"standard"
BODY_TYPE"PLUMBING"
HDL_TAP"TRUE";
"B \NAC \NWC"1;
"S \NAC"
BN"7"94;
%"Q_CAP_DIFFBUS"
"2","(-2400,1000)","2","pure_quanta","I18";
;
LOCATION"C6545"
$SEC"1"
CDS_SEC"1"
VALUE"DIFF BUS_0.22UF"
CDS_LIB"pure_quanta"
CDS_LMAN_SYM_OUTLINE"-25,50,25,-50"
PIN_NAMES_ROTATE"TRUE"
VOLTAGE"6.3V"
MATERIAL"X6S"
PACK_TYPE"C0201"
TOLERANCE"20%"
PART_NUMBER"SP_CH4221MEE01"
LOCATION"C6545";
"2"
$PN"2"97;
"1"
$PN"1"92;
%"Q_CAP_DIFFBUS"
"2","(-2400,950)","2","pure_quanta","I19";
;
LOCATION"C6546"
$SEC"1"
CDS_SEC"1"
VALUE"DIFF BUS_0.22UF"
CDS_LMAN_SYM_OUTLINE"-25,50,25,-50"
CDS_LIB"pure_quanta"
PIN_NAMES_ROTATE"TRUE"
VOLTAGE"6.3V"
MATERIAL"X6S"
PACK_TYPE"C0201"
TOLERANCE"20%"
PART_NUMBER"SP_CH4221MEE01"
LOCATION"C6546";
"2"
$PN"2"105;
"1"
$PN"1"93;
%"Q_CAP_DIFFBUS"
"2","(-2400,1200)","2","pure_quanta","I20";
;
LOCATION"C6543"
$SEC"1"
CDS_SEC"1"
VALUE"DIFF BUS_0.22UF"
CDS_LMAN_SYM_OUTLINE"-25,50,25,-50"
CDS_LIB"pure_quanta"
PIN_NAMES_ROTATE"TRUE"
VOLTAGE"6.3V"
MATERIAL"X6S"
PACK_TYPE"C0201"
TOLERANCE"20%"
PART_NUMBER"SP_CH4221MEE01"
LOCATION"C6543";
"2"
$PN"2"96;
"1"
$PN"1"91;
%"Q_CAP_DIFFBUS"
"2","(-2400,1150)","2","pure_quanta","I21";
;
LOCATION"C6544"
$SEC"1"
CDS_SEC"1"
VALUE"DIFF BUS_0.22UF"
CDS_LMAN_SYM_OUTLINE"-25,50,25,-50"
CDS_LIB"pure_quanta"
PIN_NAMES_ROTATE"TRUE"
VOLTAGE"6.3V"
MATERIAL"X6S"
PACK_TYPE"C0201"
TOLERANCE"20%"
PART_NUMBER"SP_CH4221MEE01"
LOCATION"C6544";
"2"
$PN"2"104;
"1"
$PN"1"90;
%"Q_CAP_DIFFBUS"
"2","(-2400,1400)","2","pure_quanta","I22";
;
LOCATION"C6541"
$SEC"1"
CDS_SEC"1"
VALUE"DIFF BUS_0.22UF"
CDS_LIB"pure_quanta"
CDS_LMAN_SYM_OUTLINE"-25,50,25,-50"
PIN_NAMES_ROTATE"TRUE"
VOLTAGE"6.3V"
MATERIAL"X6S"
PACK_TYPE"C0201"
TOLERANCE"20%"
PART_NUMBER"SP_CH4221MEE01"
LOCATION"C6541";
"2"
$PN"2"88;
"1"
$PN"1"87;
%"Q_CAP_DIFFBUS"
"2","(-2400,1350)","2","pure_quanta","I23";
;
LOCATION"C6542"
$SEC"1"
CDS_SEC"1"
VALUE"DIFF BUS_0.22UF"
CDS_LIB"pure_quanta"
CDS_LMAN_SYM_OUTLINE"-25,50,25,-50"
PIN_NAMES_ROTATE"TRUE"
VOLTAGE"6.3V"
MATERIAL"X6S"
PACK_TYPE"C0201"
TOLERANCE"20%"
PART_NUMBER"SP_CH4221MEE01"
LOCATION"C6542";
"2"
$PN"2"103;
"1"
$PN"1"89;
%"Q_CAP_DIFFBUS"
"2","(-2400,1550)","2","pure_quanta","I24";
;
LOCATION"C6540"
$SEC"1"
CDS_SEC"1"
VALUE"DIFF BUS_0.22UF"
CDS_LMAN_SYM_OUTLINE"-25,50,25,-50"
CDS_LIB"pure_quanta"
PIN_NAMES_ROTATE"TRUE"
VOLTAGE"6.3V"
MATERIAL"X6S"
PACK_TYPE"C0201"
TOLERANCE"20%"
PART_NUMBER"SP_CH4221MEE01"
LOCATION"C6540";
"2"
$PN"2"102;
"1"
$PN"1"82;
%"Q_CAP_DIFFBUS"
"2","(-2400,1600)","2","pure_quanta","I25";
;
LOCATION"C6539"
$SEC"1"
CDS_SEC"1"
VALUE"DIFF BUS_0.22UF"
CDS_LMAN_SYM_OUTLINE"-25,50,25,-50"
CDS_LIB"pure_quanta"
PIN_NAMES_ROTATE"TRUE"
VOLTAGE"6.3V"
MATERIAL"X6S"
PACK_TYPE"C0201"
TOLERANCE"20%"
PART_NUMBER"SP_CH4221MEE01"
LOCATION"C6539";
"2"
$PN"2"86;
"1"
$PN"1"81;
%"Q_CAP_DIFFBUS"
"2","(-2400,1750)","2","pure_quanta","I26";
;
LOCATION"C6538"
$SEC"1"
CDS_SEC"1"
VALUE"DIFF BUS_0.22UF"
CDS_LMAN_SYM_OUTLINE"-25,50,25,-50"
CDS_LIB"pure_quanta"
PIN_NAMES_ROTATE"TRUE"
VOLTAGE"6.3V"
MATERIAL"X6S"
PACK_TYPE"C0201"
TOLERANCE"20%"
PART_NUMBER"SP_CH4221MEE01"
LOCATION"C6538";
"2"
$PN"2"101;
"1"
$PN"1"80;
%"Q_CAP_DIFFBUS"
"2","(-2400,1800)","2","pure_quanta","I27";
;
LOCATION"C6537"
$SEC"1"
CDS_SEC"1"
VALUE"DIFF BUS_0.22UF"
CDS_LMAN_SYM_OUTLINE"-25,50,25,-50"
CDS_LIB"pure_quanta"
PIN_NAMES_ROTATE"TRUE"
VOLTAGE"6.3V"
MATERIAL"X6S"
PACK_TYPE"C0201"
TOLERANCE"20%"
PART_NUMBER"SP_CH4221MEE01"
LOCATION"C6537";
"2"
$PN"2"85;
"1"
$PN"1"79;
%"TAP"
"1","(-1850,800)","0","standard","I28";
;
CDS_LIB"standard"
BODY_TYPE"PLUMBING"
HDL_TAP"TRUE";
"B \NAC \NWC"2;
"S \NAC"
BN"7"95;
%"TAP"
"1","(-1850,1200)","0","standard","I29";
;
CDS_LIB"standard"
BODY_TYPE"PLUMBING"
HDL_TAP"TRUE";
"B \NAC \NWC"2;
"S \NAC"
BN"5"91;
%"TAP"
"1","(-3375,750)","2","standard","I3";
;
CDS_LIB"standard"
BODY_TYPE"PLUMBING"
HDL_TAP"TRUE";
"B \NAC \NWC"3;
"S \NAC"
BN"7"106;
%"TAP"
"1","(-1850,1000)","0","standard","I30";
;
CDS_LIB"standard"
BODY_TYPE"PLUMBING"
HDL_TAP"TRUE";
"B \NAC \NWC"2;
"S \NAC"
BN"6"92;
%"TAP"
"1","(-1650,950)","0","standard","I31";
;
CDS_LIB"standard"
BODY_TYPE"PLUMBING"
HDL_TAP"TRUE";
"B \NAC \NWC"1;
"S \NAC"
BN"6"93;
%"TAP"
"1","(-1650,1150)","0","standard","I32";
;
CDS_LIB"standard"
BODY_TYPE"PLUMBING"
HDL_TAP"TRUE";
"B \NAC \NWC"1;
"S \NAC"
BN"5"90;
%"TAP"
"1","(-1850,1600)","0","standard","I33";
;
CDS_LIB"standard"
BODY_TYPE"PLUMBING"
HDL_TAP"TRUE";
"B \NAC \NWC"2;
"S \NAC"
BN"3"81;
%"TAP"
"1","(-1850,1800)","0","standard","I34";
;
CDS_LIB"standard"
BODY_TYPE"PLUMBING"
HDL_TAP"TRUE";
"B \NAC \NWC"2;
"S \NAC"
BN"2"79;
%"TAP"
"1","(-1850,1400)","0","standard","I35";
;
CDS_LIB"standard"
BODY_TYPE"PLUMBING"
HDL_TAP"TRUE";
"B \NAC \NWC"2;
"S \NAC"
BN"4"87;
%"TAP"
"1","(-1650,1550)","0","standard","I36";
;
CDS_LIB"standard"
BODY_TYPE"PLUMBING"
HDL_TAP"TRUE";
"B \NAC \NWC"1;
"S \NAC"
BN"3"82;
%"TAP"
"1","(-1650,1350)","0","standard","I37";
;
CDS_LIB"standard"
BODY_TYPE"PLUMBING"
HDL_TAP"TRUE";
"B \NAC \NWC"1;
"S \NAC"
BN"4"89;
%"TAP"
"1","(-1650,1750)","0","standard","I38";
;
CDS_LIB"standard"
BODY_TYPE"PLUMBING"
HDL_TAP"TRUE";
"B \NAC \NWC"1;
"S \NAC"
BN"2"80;
%"TAP"
"1","(-3375,1950)","2","standard","I39";
;
CDS_LIB"standard"
BODY_TYPE"PLUMBING"
HDL_TAP"TRUE";
"B \NAC \NWC"3;
"S \NAC"
BN"1"100;
%"TAP"
"1","(-3375,950)","2","standard","I4";
;
CDS_LIB"standard"
BODY_TYPE"PLUMBING"
HDL_TAP"TRUE";
"B \NAC \NWC"3;
"S \NAC"
BN"6"105;
%"TAP"
"1","(-3375,2150)","2","standard","I40";
;
CDS_LIB"standard"
BODY_TYPE"PLUMBING"
HDL_TAP"TRUE";
"B \NAC \NWC"3;
"S \NAC"
BN"0"99;
%"TAP"
"1","(-3125,2000)","2","standard","I41";
;
CDS_LIB"standard"
BODY_TYPE"PLUMBING"
HDL_TAP"TRUE";
"B \NAC \NWC"4;
"S \NAC"
BN"1"84;
%"TAP"
"1","(-3125,2200)","2","standard","I42";
;
CDS_LIB"standard"
BODY_TYPE"PLUMBING"
HDL_TAP"TRUE";
"B \NAC \NWC"4;
"S \NAC"
BN"0"83;
%"PT5161LRS"
"10","(-7775,4575)","0","pure_quanta","I43";
;
LOCATION"U6011"
$SEC"10"
CDS_SEC"10"
MATERIAL"IC"
PART_TYPE"SMLF"
VALUE"PT5161LRS"
NEEDS_NO_SIZE"TRUE"
CDS_LMAN_SYM_OUTLINE"-350,1450,300,-1400"
CDS_LIB"pure_quanta"
PART_NUMBER"AJ051610U03";
"B_PETN7"
$PN"CC10"38;
"B_PETP7"
$PN"CA7"32;
"B_PETN6"
$PN"BT10"33;
"B_PETP6"
$PN"BP7"13;
"B_PETN5"
$PN"BJ10"34;
"B_PETP5"
$PN"BG7"35;
"B_PETN4"
$PN"BB10"36;
"B_PETP4"
$PN"AY7"17;
"B_PETN3"
$PN"AR10"18;
"B_PETP3"
$PN"AN7"37;
"B_PETN2"
$PN"AH10"26;
"B_PETP2"
$PN"AF7"16;
"B_PETN1"
$PN"AA10"15;
"B_PETP1"
$PN"W7"14;
"B_PETN0"
$PN"P10"30;
"B_PETP0"
$PN"M7"31;
%"Q_CAP_DIFFBUS"
"2","(-2400,1950)","2","pure_quanta","I44";
;
LOCATION"C6536"
$SEC"1"
CDS_SEC"1"
VALUE"DIFF BUS_0.22UF"
CDS_LMAN_SYM_OUTLINE"-25,50,25,-50"
CDS_LIB"pure_quanta"
PIN_NAMES_ROTATE"TRUE"
VOLTAGE"6.3V"
MATERIAL"X6S"
PACK_TYPE"C0201"
TOLERANCE"20%"
PART_NUMBER"SP_CH4221MEE01"
LOCATION"C6536";
"2"
$PN"2"100;
"1"
$PN"1"77;
%"Q_CAP_DIFFBUS"
"2","(-2400,2000)","2","pure_quanta","I45";
;
LOCATION"C6535"
$SEC"1"
CDS_SEC"1"
VALUE"DIFF BUS_0.22UF"
CDS_LMAN_SYM_OUTLINE"-25,50,25,-50"
CDS_LIB"pure_quanta"
PIN_NAMES_ROTATE"TRUE"
VOLTAGE"6.3V"
MATERIAL"X6S"
PACK_TYPE"C0201"
TOLERANCE"20%"
PART_NUMBER"SP_CH4221MEE01"
LOCATION"C6535";
"2"
$PN"2"84;
"1"
$PN"1"78;
%"Q_CAP_DIFFBUS"
"2","(-2400,2200)","2","pure_quanta","I46";
;
LOCATION"C6533"
$SEC"1"
CDS_SEC"1"
VALUE"DIFF BUS_0.22UF"
PACK_TYPE"C0201"
MATERIAL"X6S"
VOLTAGE"6.3V"
TOLERANCE"20%"
CDS_LIB"pure_quanta"
CDS_LMAN_SYM_OUTLINE"-25,50,25,-50"
PIN_NAMES_ROTATE"TRUE"
PART_NUMBER"SP_CH4221MEE01"
LOCATION"C6533";
"2"
$PN"2"83;
"1"
$PN"1"107;
%"Q_CAP_DIFFBUS"
"2","(-2400,2150)","2","pure_quanta","I47";
;
LOCATION"C6534"
$SEC"1"
CDS_SEC"1"
VALUE"DIFF BUS_0.22UF"
CDS_LMAN_SYM_OUTLINE"-25,50,25,-50"
CDS_LIB"pure_quanta"
PIN_NAMES_ROTATE"TRUE"
VOLTAGE"6.3V"
MATERIAL"X6S"
PACK_TYPE"C0201"
TOLERANCE"20%"
PART_NUMBER"SP_CH4221MEE01"
LOCATION"C6534";
"2"
$PN"2"99;
"1"
$PN"1"108;
%"TAP"
"1","(-1850,2000)","0","standard","I48";
;
CDS_LIB"standard"
BODY_TYPE"PLUMBING"
HDL_TAP"TRUE";
"B \NAC \NWC"2;
"S \NAC"
BN"1"78;
%"TAP"
"1","(-1850,2200)","0","standard","I49";
;
CDS_LIB"standard"
BODY_TYPE"PLUMBING"
HDL_TAP"TRUE";
"B \NAC \NWC"2;
"S \NAC"
BN"0"107;
%"TAP"
"1","(-3375,1150)","2","standard","I5";
;
CDS_LIB"standard"
BODY_TYPE"PLUMBING"
HDL_TAP"TRUE";
"B \NAC \NWC"3;
"S \NAC"
BN"5"104;
%"TAP"
"1","(-1650,1950)","0","standard","I50";
;
CDS_LIB"standard"
BODY_TYPE"PLUMBING"
HDL_TAP"TRUE";
"B \NAC \NWC"1;
"S \NAC"
BN"1"77;
%"TAP"
"1","(-1650,2150)","0","standard","I51";
;
CDS_LIB"standard"
BODY_TYPE"PLUMBING"
HDL_TAP"TRUE";
"B \NAC \NWC"1;
"S \NAC"
BN"0"108;
%"TAP"
"1","(-6850,3275)","0","standard","I52";
;
CDS_LIB"standard"
BODY_TYPE"PLUMBING"
HDL_TAP"TRUE";
"B \NAC \NWC"11;
"S \NAC"
BN"8"38;
%"TAP"
"1","(-7050,3375)","0","standard","I53";
;
CDS_LIB"standard"
BODY_TYPE"PLUMBING"
HDL_TAP"TRUE";
"B \NAC \NWC"12;
"S \NAC"
BN"8"32;
%"TAP"
"1","(-6850,3625)","0","standard","I54";
;
CDS_LIB"standard"
BODY_TYPE"PLUMBING"
HDL_TAP"TRUE";
"B \NAC \NWC"11;
"S \NAC"
BN"9"33;
%"TAP"
"1","(-7050,3725)","0","standard","I55";
;
CDS_LIB"standard"
BODY_TYPE"PLUMBING"
HDL_TAP"TRUE";
"B \NAC \NWC"12;
"S \NAC"
BN"9"13;
%"TAP"
"1","(-3375,1350)","2","standard","I6";
;
CDS_LIB"standard"
BODY_TYPE"PLUMBING"
HDL_TAP"TRUE";
"B \NAC \NWC"3;
"S \NAC"
BN"4"103;
%"TAP"
"1","(-6850,3975)","0","standard","I60";
;
CDS_LIB"standard"
BODY_TYPE"PLUMBING"
HDL_TAP"TRUE";
"B \NAC \NWC"11;
"S \NAC"
BN"10"34;
%"TAP"
"1","(-7050,4075)","0","standard","I61";
;
CDS_LIB"standard"
BODY_TYPE"PLUMBING"
HDL_TAP"TRUE";
"B \NAC \NWC"12;
"S \NAC"
BN"10"35;
%"TAP"
"1","(-6850,4325)","0","standard","I62";
;
CDS_LIB"standard"
BODY_TYPE"PLUMBING"
HDL_TAP"TRUE";
"B \NAC \NWC"11;
"S \NAC"
BN"11"36;
%"TAP"
"1","(-7050,4425)","0","standard","I63";
;
CDS_LIB"standard"
BODY_TYPE"PLUMBING"
HDL_TAP"TRUE";
"B \NAC \NWC"12;
"S \NAC"
BN"11"17;
%"TAP"
"1","(-7050,4775)","0","standard","I64";
;
CDS_LIB"standard"
BODY_TYPE"PLUMBING"
HDL_TAP"TRUE";
"B \NAC \NWC"12;
"S \NAC"
BN"12"37;
%"TAP"
"1","(-6850,4675)","0","standard","I65";
;
CDS_LIB"standard"
BODY_TYPE"PLUMBING"
HDL_TAP"TRUE";
"B \NAC \NWC"11;
"S \NAC"
BN"12"18;
%"TAP"
"1","(-6850,5025)","0","standard","I66";
;
CDS_LIB"standard"
BODY_TYPE"PLUMBING"
HDL_TAP"TRUE";
"B \NAC \NWC"11;
"S \NAC"
BN"13"26;
%"TAP"
"1","(-7050,5125)","0","standard","I67";
;
CDS_LIB"standard"
BODY_TYPE"PLUMBING"
HDL_TAP"TRUE";
"B \NAC \NWC"12;
"S \NAC"
BN"13"16;
%"TAP"
"1","(-6850,5375)","0","standard","I68";
;
CDS_LIB"standard"
BODY_TYPE"PLUMBING"
HDL_TAP"TRUE";
"B \NAC \NWC"11;
"S \NAC"
BN"14"15;
%"TAP"
"1","(-7050,5475)","0","standard","I69";
;
CDS_LIB"standard"
BODY_TYPE"PLUMBING"
HDL_TAP"TRUE";
"B \NAC \NWC"12;
"S \NAC"
BN"14"14;
%"TAP"
"1","(-3375,1550)","2","standard","I7";
;
CDS_LIB"standard"
BODY_TYPE"PLUMBING"
HDL_TAP"TRUE";
"B \NAC \NWC"3;
"S \NAC"
BN"3"102;
%"TAP"
"1","(-6850,5725)","0","standard","I70";
;
CDS_LIB"standard"
BODY_TYPE"PLUMBING"
HDL_TAP"TRUE";
"B \NAC \NWC"11;
"S \NAC"
BN"15"30;
%"TAP"
"1","(-7050,5825)","0","standard","I71";
;
CDS_LIB"standard"
BODY_TYPE"PLUMBING"
HDL_TAP"TRUE";
"B \NAC \NWC"12;
"S \NAC"
BN"15"31;
%"TAP"
"1","(-7900,750)","2","standard","I74";
;
CDS_LIB"standard"
BODY_TYPE"PLUMBING"
HDL_TAP"TRUE";
"B \NAC \NWC"7;
"S \NAC"
BN"15"74;
%"TAP"
"1","(-7650,800)","2","standard","I75";
;
CDS_LIB"standard"
BODY_TYPE"PLUMBING"
HDL_TAP"TRUE";
"B \NAC \NWC"8;
"S \NAC"
BN"15"72;
%"TAP"
"1","(-7900,950)","2","standard","I76";
;
CDS_LIB"standard"
BODY_TYPE"PLUMBING"
HDL_TAP"TRUE";
"B \NAC \NWC"7;
"S \NAC"
BN"14"73;
%"TAP"
"1","(-7900,1150)","2","standard","I77";
;
CDS_LIB"standard"
BODY_TYPE"PLUMBING"
HDL_TAP"TRUE";
"B \NAC \NWC"7;
"S \NAC"
BN"13"68;
%"TAP"
"1","(-7900,1350)","2","standard","I78";
;
CDS_LIB"standard"
BODY_TYPE"PLUMBING"
HDL_TAP"TRUE";
"B \NAC \NWC"7;
"S \NAC"
BN"12"69;
%"TAP"
"1","(-7650,1000)","2","standard","I79";
;
CDS_LIB"standard"
BODY_TYPE"PLUMBING"
HDL_TAP"TRUE";
"B \NAC \NWC"8;
"S \NAC"
BN"14"71;
%"TAP"
"1","(-3375,1750)","2","standard","I8";
;
CDS_LIB"standard"
BODY_TYPE"PLUMBING"
HDL_TAP"TRUE";
"B \NAC \NWC"3;
"S \NAC"
BN"2"101;
%"TAP"
"1","(-7650,1200)","2","standard","I80";
;
CDS_LIB"standard"
BODY_TYPE"PLUMBING"
HDL_TAP"TRUE";
"B \NAC \NWC"8;
"S \NAC"
BN"13"67;
%"TAP"
"1","(-7900,1550)","2","standard","I81";
;
CDS_LIB"standard"
BODY_TYPE"PLUMBING"
HDL_TAP"TRUE";
"B \NAC \NWC"7;
"S \NAC"
BN"11"70;
%"TAP"
"1","(-7900,1750)","2","standard","I82";
;
CDS_LIB"standard"
BODY_TYPE"PLUMBING"
HDL_TAP"TRUE";
"B \NAC \NWC"7;
"S \NAC"
BN"10"64;
%"TAP"
"1","(-7650,1600)","2","standard","I83";
;
CDS_LIB"standard"
BODY_TYPE"PLUMBING"
HDL_TAP"TRUE";
"B \NAC \NWC"8;
"S \NAC"
BN"11"63;
%"TAP"
"1","(-7650,1400)","2","standard","I84";
;
CDS_LIB"standard"
BODY_TYPE"PLUMBING"
HDL_TAP"TRUE";
"B \NAC \NWC"8;
"S \NAC"
BN"12"66;
%"TAP"
"1","(-7650,1800)","2","standard","I85";
;
CDS_LIB"standard"
BODY_TYPE"PLUMBING"
HDL_TAP"TRUE";
"B \NAC \NWC"8;
"S \NAC"
BN"10"62;
%"Q_CAP_DIFFBUS"
"2","(-6925,750)","2","pure_quanta","I86";
;
LOCATION"C6564"
$SEC"1"
CDS_SEC"1"
VALUE"DIFF BUS_0.22UF"
TOLERANCE"20%"
PACK_TYPE"C0201"
MATERIAL"X6S"
VOLTAGE"6.3V"
PIN_NAMES_ROTATE"TRUE"
CDS_LIB"pure_quanta"
CDS_LMAN_SYM_OUTLINE"-25,50,25,-50"
PART_NUMBER"SP_CH4221MEE01"
LOCATION"C6564";
"2"
$PN"2"74;
"1"
$PN"1"60;
%"Q_CAP_DIFFBUS"
"2","(-6925,800)","2","pure_quanta","I87";
;
LOCATION"C6563"
$SEC"1"
CDS_SEC"1"
VALUE"DIFF BUS_0.22UF"
TOLERANCE"20%"
PACK_TYPE"C0201"
MATERIAL"X6S"
VOLTAGE"6.3V"
PIN_NAMES_ROTATE"TRUE"
CDS_LIB"pure_quanta"
CDS_LMAN_SYM_OUTLINE"-25,50,25,-50"
PART_NUMBER"SP_CH4221MEE01"
LOCATION"C6563";
"2"
$PN"2"72;
"1"
$PN"1"59;
%"Q_CAP_DIFFBUS"
"2","(-6925,950)","2","pure_quanta","I88";
;
LOCATION"C6562"
$SEC"1"
CDS_SEC"1"
VALUE"DIFF BUS_0.22UF"
TOLERANCE"20%"
PACK_TYPE"C0201"
MATERIAL"X6S"
VOLTAGE"6.3V"
PIN_NAMES_ROTATE"TRUE"
CDS_LIB"pure_quanta"
CDS_LMAN_SYM_OUTLINE"-25,50,25,-50"
PART_NUMBER"SP_CH4221MEE01"
LOCATION"C6562";
"2"
$PN"2"73;
"1"
$PN"1"58;
%"Q_CAP_DIFFBUS"
"2","(-6925,1000)","2","pure_quanta","I89";
;
LOCATION"C6561"
$SEC"1"
CDS_SEC"1"
VALUE"DIFF BUS_0.22UF"
TOLERANCE"20%"
PACK_TYPE"C0201"
MATERIAL"X6S"
VOLTAGE"6.3V"
PIN_NAMES_ROTATE"TRUE"
CDS_LMAN_SYM_OUTLINE"-25,50,25,-50"
CDS_LIB"pure_quanta"
PART_NUMBER"SP_CH4221MEE01"
LOCATION"C6561";
"2"
$PN"2"71;
"1"
$PN"1"57;
%"TAP"
"1","(-3125,800)","2","standard","I9";
;
CDS_LIB"standard"
BODY_TYPE"PLUMBING"
HDL_TAP"TRUE";
"B \NAC \NWC"4;
"S \NAC"
BN"7"98;
%"Q_CAP_DIFFBUS"
"2","(-6925,1150)","2","pure_quanta","I90";
;
LOCATION"C6560"
$SEC"1"
CDS_SEC"1"
VALUE"DIFF BUS_0.22UF"
TOLERANCE"20%"
PACK_TYPE"C0201"
MATERIAL"X6S"
VOLTAGE"6.3V"
PIN_NAMES_ROTATE"TRUE"
CDS_LIB"pure_quanta"
CDS_LMAN_SYM_OUTLINE"-25,50,25,-50"
PART_NUMBER"SP_CH4221MEE01"
LOCATION"C6560";
"2"
$PN"2"68;
"1"
$PN"1"56;
%"Q_CAP_DIFFBUS"
"2","(-6925,1200)","2","pure_quanta","I91";
;
LOCATION"C6559"
$SEC"1"
CDS_SEC"1"
VALUE"DIFF BUS_0.22UF"
TOLERANCE"20%"
PACK_TYPE"C0201"
MATERIAL"X6S"
VOLTAGE"6.3V"
PIN_NAMES_ROTATE"TRUE"
CDS_LIB"pure_quanta"
CDS_LMAN_SYM_OUTLINE"-25,50,25,-50"
PART_NUMBER"SP_CH4221MEE01"
LOCATION"C6559";
"2"
$PN"2"67;
"1"
$PN"1"55;
%"Q_CAP_DIFFBUS"
"2","(-6925,1350)","2","pure_quanta","I92";
;
LOCATION"C6558"
$SEC"1"
CDS_SEC"1"
VALUE"DIFF BUS_0.22UF"
TOLERANCE"20%"
PACK_TYPE"C0201"
MATERIAL"X6S"
VOLTAGE"6.3V"
PIN_NAMES_ROTATE"TRUE"
CDS_LMAN_SYM_OUTLINE"-25,50,25,-50"
CDS_LIB"pure_quanta"
PART_NUMBER"SP_CH4221MEE01"
LOCATION"C6558";
"2"
$PN"2"69;
"1"
$PN"1"54;
%"Q_CAP_DIFFBUS"
"2","(-6925,1400)","2","pure_quanta","I93";
;
LOCATION"C6557"
$SEC"1"
CDS_SEC"1"
VALUE"DIFF BUS_0.22UF"
TOLERANCE"20%"
PACK_TYPE"C0201"
MATERIAL"X6S"
VOLTAGE"6.3V"
PIN_NAMES_ROTATE"TRUE"
CDS_LMAN_SYM_OUTLINE"-25,50,25,-50"
CDS_LIB"pure_quanta"
PART_NUMBER"SP_CH4221MEE01"
LOCATION"C6557";
"2"
$PN"2"66;
"1"
$PN"1"53;
%"Q_CAP_DIFFBUS"
"2","(-6925,1550)","2","pure_quanta","I94";
;
LOCATION"C6556"
$SEC"1"
CDS_SEC"1"
VALUE"DIFF BUS_0.22UF"
TOLERANCE"20%"
PACK_TYPE"C0201"
MATERIAL"X6S"
VOLTAGE"6.3V"
PIN_NAMES_ROTATE"TRUE"
CDS_LIB"pure_quanta"
CDS_LMAN_SYM_OUTLINE"-25,50,25,-50"
PART_NUMBER"SP_CH4221MEE01"
LOCATION"C6556";
"2"
$PN"2"70;
"1"
$PN"1"52;
%"Q_CAP_DIFFBUS"
"2","(-6925,1600)","2","pure_quanta","I95";
;
LOCATION"C6555"
$SEC"1"
CDS_SEC"1"
VALUE"DIFF BUS_0.22UF"
TOLERANCE"20%"
PACK_TYPE"C0201"
MATERIAL"X6S"
VOLTAGE"6.3V"
PIN_NAMES_ROTATE"TRUE"
CDS_LIB"pure_quanta"
CDS_LMAN_SYM_OUTLINE"-25,50,25,-50"
PART_NUMBER"SP_CH4221MEE01"
LOCATION"C6555";
"2"
$PN"2"63;
"1"
$PN"1"51;
%"Q_CAP_DIFFBUS"
"2","(-6925,1800)","2","pure_quanta","I96";
;
LOCATION"C6553"
$SEC"1"
CDS_SEC"1"
VALUE"DIFF BUS_0.22UF"
TOLERANCE"20%"
PACK_TYPE"C0201"
MATERIAL"X6S"
VOLTAGE"6.3V"
PIN_NAMES_ROTATE"TRUE"
CDS_LIB"pure_quanta"
CDS_LMAN_SYM_OUTLINE"-25,50,25,-50"
PART_NUMBER"SP_CH4221MEE01"
LOCATION"C6553";
"2"
$PN"2"62;
"1"
$PN"1"75;
%"Q_CAP_DIFFBUS"
"2","(-6925,1750)","2","pure_quanta","I97";
;
LOCATION"C6554"
$SEC"1"
CDS_SEC"1"
VALUE"DIFF BUS_0.22UF"
TOLERANCE"20%"
PACK_TYPE"C0201"
MATERIAL"X6S"
VOLTAGE"6.3V"
PIN_NAMES_ROTATE"TRUE"
CDS_LIB"pure_quanta"
CDS_LMAN_SYM_OUTLINE"-25,50,25,-50"
PART_NUMBER"SP_CH4221MEE01"
LOCATION"C6554";
"2"
$PN"2"64;
"1"
$PN"1"76;
%"TAP"
"1","(-7900,1950)","2","standard","I98";
;
CDS_LIB"standard"
BODY_TYPE"PLUMBING"
HDL_TAP"TRUE";
"B \NAC \NWC"7;
"S \NAC"
BN"9"65;
%"TAP"
"1","(-7900,2150)","2","standard","I99";
;
CDS_LIB"standard"
BODY_TYPE"PLUMBING"
HDL_TAP"TRUE";
"B \NAC \NWC"7;
"S \NAC"
BN"8"48;
END.
